# T6G (Grand Teton) — schematic netlist excerpt (pin names and nets, part order shuffled) for the footprints in the layout excerpt that follows; sources: Cadence DE-HDL packaged netlist, KiCad conversion of 04192023_DAF0TMB3IC0_F0TG_MB_C_brd_V02_OCP.brd

C230  Q_CAP  0.001UF 50V 10% EMPTY  pkg C0402  page 54 : A = JTAG_CPU1_TDO ; B = GND
R300  Q_RES  1K 1% CHIP  pkg 0402LF  page 95 : A = PWRGD_CHJ_CPU0_DIMM ; B = PWRGD_CHGL_CPU0
R6738  Q_RES  1K 1% CHIP  pkg 0201LF  page 184 : A = P1V8_CPU1_RT_1D ; B = SMB_RT_CPU1_P1_R_SDA

(kicad_pcb
	(version 20260206)
	(generator "pcbnew")
	(generator_version "10.0")
	(general
		(thickness 1.6)
		(legacy_teardrops no)
	)
	(paper "A4")
	(title_block
		(title "04192023_DAF0TMB3IC0_F0TG_MB_C_brd_V02_OCP.brd")
		(comment 1 "Grand Teton / footprints 6179-6181 of 8354")
	)
	(layers
		(0 "F.Cu" signal "TOP")
		(4 "In1.Cu" signal "GND")
		(6 "In2.Cu" signal "IN1")
		(8 "In3.Cu" signal "GND1")
		(10 "In4.Cu" signal "IN2")
		(12 "In5.Cu" signal "GND2")
		(14 "In6.Cu" signal "IN3")
		(16 "In7.Cu" signal "GND3")
		(18 "In8.Cu" signal "VCC")
		(20 "In9.Cu" signal "VCC1")
		(22 "In10.Cu" signal "GND4")
		(24 "In11.Cu" signal "IN4")
		(26 "In12.Cu" signal "GND5")
		(28 "In13.Cu" signal "IN5")
		(30 "In14.Cu" signal "GND6")
		(32 "In15.Cu" signal "IN6")
		(34 "In16.Cu" signal "GND7")
		(2 "B.Cu" signal "BOTTOM")
		(9 "F.Adhes" user "F.Adhesive")
		(11 "B.Adhes" user "B.Adhesive")
		(13 "F.Paste" user "Package Geometry/Pastemask Top")
		(15 "B.Paste" user "Package Geometry/Pastemask Bottom")
		(5 "F.SilkS" user "Ref Des/Silkscreen Top")
		(7 "B.SilkS" user "Ref Des/Silkscreen Bottom")
		(1 "F.Mask" user "Board Geometry/Soldermask Top")
		(3 "B.Mask" user "Board Geometry/Soldermask Bottom")
		(17 "Dwgs.User" user "User.Drawings")
		(19 "Cmts.User" user "User.Comments")
		(21 "Eco1.User" user "User.Eco1")
		(23 "Eco2.User" user "User.Eco2")
		(25 "Edge.Cuts" user "Board Geometry/Outline")
		(27 "Margin" user)
		(31 "F.CrtYd" user "Package Geometry/Place Bound Top")
		(29 "B.CrtYd" user "Package Geometry/Place Bound Bottom")
		(35 "F.Fab" user "Ref Des/Assembly Top")
		(33 "B.Fab" user "Ref Des/Assembly Bottom")
	)
	(footprint ""
		(layer "B.Cu")
		(at 154.348434 -199.234552 -90)
		(property "Reference" "C230"
			(at 0 0 90)
			(layer "B.SilkS")
			(hide yes)
			(effects
				(font
					(size 1.27 1.27)
				)
				(justify mirror)
			)
		)
		(property "Value" ""
			(at 0 0 90)
			(layer "B.Fab")
			(effects
				(font
					(size 1.27 1.27)
				)
				(justify mirror)
			)
		)
		(duplicate_pad_numbers_are_jumpers no)
		(fp_line
			(start -0.7874 0.4064)
			(end 0.7874 0.4064)
			(stroke
				(width 0.1524)
				(type default)
			)
			(layer "B.SilkS")
		)
		(fp_line
			(start 0.7874 0.4064)
			(end 0.7874 -0.4064)
			(stroke
				(width 0.1524)
				(type default)
			)
			(layer "B.SilkS")
		)
		(fp_line
			(start -0.7874 -0.4064)
			(end -0.7874 0.4064)
			(stroke
				(width 0.1524)
				(type default)
			)
			(layer "B.SilkS")
		)
		(fp_line
			(start 0.7874 -0.4064)
			(end -0.7874 -0.4064)
			(stroke
				(width 0.1524)
				(type default)
			)
			(layer "B.SilkS")
		)
		(fp_line
			(start -0.67945 0.3048)
			(end -0.120396 0.3048)
			(stroke
				(width 0.1)
				(type default)
			)
			(layer "B.Fab")
		)
		(fp_line
			(start -0.120396 0.3048)
			(end -0.120396 0.2794)
			(stroke
				(width 0.1)
				(type default)
			)
			(layer "B.Fab")
		)
		(fp_line
			(start 0.12065 0.3048)
			(end 0.67945 0.3048)
			(stroke
				(width 0.1)
				(type default)
			)
			(layer "B.Fab")
		)
		(fp_line
			(start 0.67945 0.3048)
			(end 0.67945 -0.305054)
			(stroke
				(width 0.1)
				(type default)
			)
			(layer "B.Fab")
		)
		(fp_line
			(start -0.120396 0.2794)
			(end 0.12065 0.2794)
			(stroke
				(width 0.1)
				(type default)
			)
			(layer "B.Fab")
		)
		(fp_line
			(start 0.12065 0.2794)
			(end 0.12065 0.3048)
			(stroke
				(width 0.1)
				(type default)
			)
			(layer "B.Fab")
		)
		(fp_line
			(start -0.12065 -0.2794)
			(end -0.12065 -0.3048)
			(stroke
				(width 0.1)
				(type default)
			)
			(layer "B.Fab")
		)
		(fp_line
			(start 0.12065 -0.2794)
			(end -0.12065 -0.2794)
			(stroke
				(width 0.1)
				(type default)
			)
			(layer "B.Fab")
		)
		(fp_line
			(start -0.67945 -0.3048)
			(end -0.67945 0.3048)
			(stroke
				(width 0.1)
				(type default)
			)
			(layer "B.Fab")
		)
		(fp_line
			(start -0.12065 -0.3048)
			(end -0.67945 -0.3048)
			(stroke
				(width 0.1)
				(type default)
			)
			(layer "B.Fab")
		)
		(fp_line
			(start 0.12065 -0.305054)
			(end 0.12065 -0.2794)
			(stroke
				(width 0.1)
				(type default)
			)
			(layer "B.Fab")
		)
		(fp_line
			(start 0.67945 -0.305054)
			(end 0.12065 -0.305054)
			(stroke
				(width 0.1)
				(type default)
			)
			(layer "B.Fab")
		)
		(pad "1" smd circle
			(at 0.40005 0 90)
			(size 0 0)
			(layers "B.Cu" "B.Mask" "B.Paste")
			(net "JTAG_CPU1_TDO")
		)
		(pad "2" smd circle
			(at -0.40005 0 90)
			(size 0 0)
			(layers "B.Cu" "B.Mask" "B.Paste")
			(net "GND")
		)
	)
	(footprint ""
		(layer "B.Cu")
		(at 434.797454 -191.20231 180)
		(property "Reference" "R300"
			(at 0 0 0)
			(layer "B.SilkS")
			(hide yes)
			(effects
				(font
					(size 1.27 1.27)
				)
				(justify mirror)
			)
		)
		(property "Value" ""
			(at 0 0 0)
			(layer "B.Fab")
			(effects
				(font
					(size 1.27 1.27)
				)
				(justify mirror)
			)
		)
		(duplicate_pad_numbers_are_jumpers no)
		(fp_line
			(start 0.7874 0.4064)
			(end 0.7874 -0.4064)
			(stroke
				(width 0.1524)
				(type default)
			)
			(layer "B.SilkS")
		)
		(fp_line
			(start 0.7874 -0.4064)
			(end -0.7874 -0.4064)
			(stroke
				(width 0.1524)
				(type default)
			)
			(layer "B.SilkS")
		)
		(fp_line
			(start -0.7874 0.4064)
			(end 0.7874 0.4064)
			(stroke
				(width 0.1524)
				(type default)
			)
			(layer "B.SilkS")
		)
		(fp_line
			(start -0.7874 -0.4064)
			(end -0.7874 0.4064)
			(stroke
				(width 0.1524)
				(type default)
			)
			(layer "B.SilkS")
		)
		(fp_line
			(start 0.67945 0.3048)
			(end 0.67945 -0.305054)
			(stroke
				(width 0.1)
				(type default)
			)
			(layer "B.Fab")
		)
		(fp_line
			(start 0.67945 -0.305054)
			(end 0.12065 -0.305054)
			(stroke
				(width 0.1)
				(type default)
			)
			(layer "B.Fab")
		)
		(fp_line
			(start 0.12065 0.3048)
			(end 0.67945 0.3048)
			(stroke
				(width 0.1)
				(type default)
			)
			(layer "B.Fab")
		)
		(fp_line
			(start 0.12065 0.2794)
			(end 0.12065 0.3048)
			(stroke
				(width 0.1)
				(type default)
			)
			(layer "B.Fab")
		)
		(fp_line
			(start 0.12065 -0.2794)
			(end -0.12065 -0.2794)
			(stroke
				(width 0.1)
				(type default)
			)
			(layer "B.Fab")
		)
		(fp_line
			(start 0.12065 -0.305054)
			(end 0.12065 -0.2794)
			(stroke
				(width 0.1)
				(type default)
			)
			(layer "B.Fab")
		)
		(fp_line
			(start -0.120396 0.3048)
			(end -0.120396 0.2794)
			(stroke
				(width 0.1)
				(type default)
			)
			(layer "B.Fab")
		)
		(fp_line
			(start -0.120396 0.2794)
			(end 0.12065 0.2794)
			(stroke
				(width 0.1)
				(type default)
			)
			(layer "B.Fab")
		)
		(fp_line
			(start -0.12065 -0.2794)
			(end -0.12065 -0.3048)
			(stroke
				(width 0.1)
				(type default)
			)
			(layer "B.Fab")
		)
		(fp_line
			(start -0.12065 -0.3048)
			(end -0.67945 -0.3048)
			(stroke
				(width 0.1)
				(type default)
			)
			(layer "B.Fab")
		)
		(fp_line
			(start -0.67945 0.3048)
			(end -0.120396 0.3048)
			(stroke
				(width 0.1)
				(type default)
			)
			(layer "B.Fab")
		)
		(fp_line
			(start -0.67945 -0.3048)
			(end -0.67945 0.3048)
			(stroke
				(width 0.1)
				(type default)
			)
			(layer "B.Fab")
		)
		(pad "1" smd circle
			(at 0.40005 0)
			(size 0 0)
			(layers "B.Cu" "B.Mask" "B.Paste")
			(net "PWRGD_CHJ_CPU0_DIMM")
		)
		(pad "2" smd circle
			(at -0.40005 0)
			(size 0 0)
			(layers "B.Cu" "B.Mask" "B.Paste")
			(net "PWRGD_CHGL_CPU0")
		)
	)
	(footprint ""
		(layer "B.Cu")
		(at 216.916 -336.169 -90)
		(property "Reference" "R6738"
			(at 0 0 90)
			(layer "B.SilkS")
			(hide yes)
			(effects
				(font
					(size 1.27 1.27)
				)
				(justify mirror)
			)
		)
		(property "Value" ""
			(at 0 0 90)
			(layer "B.Fab")
			(effects
				(font
					(size 1.27 1.27)
				)
				(justify mirror)
			)
		)
		(duplicate_pad_numbers_are_jumpers no)
		(fp_line
			(start -0.32512 0.175006)
			(end 0.32512 0.175006)
			(stroke
				(width 0.1)
				(type default)
			)
			(layer "B.Fab")
		)
		(fp_line
			(start 0.32512 0.175006)
			(end 0.32512 -0.175006)
			(stroke
				(width 0.1)
				(type default)
			)
			(layer "B.Fab")
		)
		(fp_line
			(start -0.32512 -0.175006)
			(end -0.32512 0.175006)
			(stroke
				(width 0.1)
				(type default)
			)
			(layer "B.Fab")
		)
		(fp_line
			(start 0.32512 -0.175006)
			(end -0.32512 -0.175006)
			(stroke
				(width 0.1)
				(type default)
			)
			(layer "B.Fab")
		)
		(pad "1" smd rect
			(at 0.2667 0 90)
			(size 0.3048 0.381)
			(layers "B.Cu" "B.Mask" "B.Paste")
			(net "P1V8_CPU1_RT_1D")
		)
		(pad "2" smd rect
			(at -0.2667 0 270)
			(size 0.3048 0.381)
			(layers "B.Cu" "B.Mask" "B.Paste")
			(net "SMB_RT_CPU1_P1_R_SDA")
		)
	)
)
